(kicad_pcb
	(version 20260206)
	(generator "pcbnew")
	(generator_version "10.0")
	(general
		(thickness 1.6)
		(legacy_teardrops no)
	)
	(paper "A4")
	(title_block
		(title "01162023_DA0F0TEBIF0_F0T_Expander_BD_F_brd_V02_OCP.brd")
		(comment 1 "Grand Teton / footprints 4820-4826 of 9728")
	)
	(layers
		(0 "F.Cu" signal "TOP")
		(4 "In1.Cu" signal "GND")
		(6 "In2.Cu" signal "VCC")
		(8 "In3.Cu" signal "VCC1")
		(10 "In4.Cu" signal "GND1")
		(12 "In5.Cu" signal "IN1")
		(14 "In6.Cu" signal "GND2")
		(16 "In7.Cu" signal "IN2")
		(18 "In8.Cu" signal "GND3")
		(20 "In9.Cu" signal "IN3")
		(22 "In10.Cu" signal "GND4")
		(24 "In11.Cu" signal "IN4")
		(26 "In12.Cu" signal "GND5")
		(28 "In13.Cu" signal "IN5")
		(30 "In14.Cu" signal "GND6")
		(32 "In15.Cu" signal "IN6")
		(34 "In16.Cu" signal "GND7")
		(2 "B.Cu" signal "BOTTOM")
		(9 "F.Adhes" user "F.Adhesive")
		(11 "B.Adhes" user "B.Adhesive")
		(13 "F.Paste" user "Package Geometry/Pastemask Top")
		(15 "B.Paste" user "Package Geometry/Pastemask Bottom")
		(5 "F.SilkS" user "Ref Des/Silkscreen Top")
		(7 "B.SilkS" user "Ref Des/Silkscreen Bottom")
		(1 "F.Mask" user "Board Geometry/Soldermask Top")
		(3 "B.Mask" user "Board Geometry/Soldermask Bottom")
		(17 "Dwgs.User" user "User.Drawings")
		(19 "Cmts.User" user "User.Comments")
		(21 "Eco1.User" user "User.Eco1")
		(23 "Eco2.User" user "User.Eco2")
		(25 "Edge.Cuts" user "Board Geometry/Outline")
		(27 "Margin" user)
		(31 "F.CrtYd" user "Package Geometry/Place Bound Top")
		(29 "B.CrtYd" user "Package Geometry/Place Bound Bottom")
		(35 "F.Fab" user "Ref Des/Assembly Top")
		(33 "B.Fab" user "Ref Des/Assembly Bottom")
	)
	(footprint ""
		(layer "F.Cu")
		(at 154.707844 -153.3144 180)
		(property "Reference" "R127"
			(at 0 0 180)
			(layer "F.SilkS")
			(hide yes)
			(effects
				(font
					(size 1.27 1.27)
				)
			)
		)
		(property "Value" ""
			(at 0 0 180)
			(layer "F.Fab")
			(effects
				(font
					(size 1.27 1.27)
				)
			)
		)
		(duplicate_pad_numbers_are_jumpers no)
		(fp_line
			(start 0.7874 0.4064)
			(end -0.7874 0.4064)
			(stroke
				(width 0.1524)
				(type default)
			)
			(layer "F.SilkS")
		)
		(fp_line
			(start 0.7874 -0.4064)
			(end 0.7874 0.4064)
			(stroke
				(width 0.1524)
				(type default)
			)
			(layer "F.SilkS")
		)
		(fp_line
			(start -0.7874 0.4064)
			(end -0.7874 -0.4064)
			(stroke
				(width 0.1524)
				(type default)
			)
			(layer "F.SilkS")
		)
		(fp_line
			(start -0.7874 -0.4064)
			(end 0.7874 -0.4064)
			(stroke
				(width 0.1524)
				(type default)
			)
			(layer "F.SilkS")
		)
		(fp_line
			(start 0.67945 0.3048)
			(end 0.120396 0.3048)
			(stroke
				(width 0.1)
				(type default)
			)
			(layer "F.Fab")
		)
		(fp_line
			(start 0.67945 -0.3048)
			(end 0.67945 0.3048)
			(stroke
				(width 0.1)
				(type default)
			)
			(layer "F.Fab")
		)
		(fp_line
			(start 0.12065 -0.2794)
			(end 0.12065 -0.3048)
			(stroke
				(width 0.1)
				(type default)
			)
			(layer "F.Fab")
		)
		(fp_line
			(start 0.12065 -0.3048)
			(end 0.67945 -0.3048)
			(stroke
				(width 0.1)
				(type default)
			)
			(layer "F.Fab")
		)
		(fp_line
			(start 0.120396 0.3048)
			(end 0.120396 0.2794)
			(stroke
				(width 0.1)
				(type default)
			)
			(layer "F.Fab")
		)
		(fp_line
			(start 0.120396 0.2794)
			(end -0.12065 0.2794)
			(stroke
				(width 0.1)
				(type default)
			)
			(layer "F.Fab")
		)
		(fp_line
			(start -0.12065 0.3048)
			(end -0.67945 0.3048)
			(stroke
				(width 0.1)
				(type default)
			)
			(layer "F.Fab")
		)
		(fp_line
			(start -0.12065 0.2794)
			(end -0.12065 0.3048)
			(stroke
				(width 0.1)
				(type default)
			)
			(layer "F.Fab")
		)
		(fp_line
			(start -0.12065 -0.2794)
			(end 0.12065 -0.2794)
			(stroke
				(width 0.1)
				(type default)
			)
			(layer "F.Fab")
		)
		(fp_line
			(start -0.12065 -0.305054)
			(end -0.12065 -0.2794)
			(stroke
				(width 0.1)
				(type default)
			)
			(layer "F.Fab")
		)
		(fp_line
			(start -0.67945 0.3048)
			(end -0.67945 -0.305054)
			(stroke
				(width 0.1)
				(type default)
			)
			(layer "F.Fab")
		)
		(fp_line
			(start -0.67945 -0.305054)
			(end -0.12065 -0.305054)
			(stroke
				(width 0.1)
				(type default)
			)
			(layer "F.Fab")
		)
		(pad "1" smd circle
			(at -0.40005 0 180)
			(size 0 0)
			(layers "F.Cu" "F.Mask" "F.Paste")
			(net "NIC2_SLOT_ID0")
		)
		(pad "2" smd circle
			(at 0.40005 0 180)
			(size 0 0)
			(layers "F.Cu" "F.Mask" "F.Paste")
			(net "P3V3_NIC2")
		)
	)
	(footprint ""
		(layer "F.Cu")
		(at 35.298634 -137.259314 -90)
		(property "Reference" "C855"
			(at 0 0 270)
			(layer "F.SilkS")
			(hide yes)
			(effects
				(font
					(size 1.27 1.27)
				)
			)
		)
		(property "Value" ""
			(at 0 0 270)
			(layer "F.Fab")
			(effects
				(font
					(size 1.27 1.27)
				)
			)
		)
		(duplicate_pad_numbers_are_jumpers no)
		(fp_line
			(start -0.7874 0.4064)
			(end -0.7874 -0.4064)
			(stroke
				(width 0.1524)
				(type default)
			)
			(layer "F.SilkS")
		)
		(fp_line
			(start 0.7874 0.4064)
			(end -0.7874 0.4064)
			(stroke
				(width 0.1524)
				(type default)
			)
			(layer "F.SilkS")
		)
		(fp_line
			(start -0.7874 -0.4064)
			(end 0.7874 -0.4064)
			(stroke
				(width 0.1524)
				(type default)
			)
			(layer "F.SilkS")
		)
		(fp_line
			(start 0.7874 -0.4064)
			(end 0.7874 0.4064)
			(stroke
				(width 0.1524)
				(type default)
			)
			(layer "F.SilkS")
		)
		(fp_line
			(start -0.67945 0.3048)
			(end -0.67945 -0.305054)
			(stroke
				(width 0.1)
				(type default)
			)
			(layer "F.Fab")
		)
		(fp_line
			(start -0.12065 0.3048)
			(end -0.67945 0.3048)
			(stroke
				(width 0.1)
				(type default)
			)
			(layer "F.Fab")
		)
		(fp_line
			(start 0.120396 0.3048)
			(end 0.120396 0.2794)
			(stroke
				(width 0.1)
				(type default)
			)
			(layer "F.Fab")
		)
		(fp_line
			(start 0.67945 0.3048)
			(end 0.120396 0.3048)
			(stroke
				(width 0.1)
				(type default)
			)
			(layer "F.Fab")
		)
		(fp_line
			(start -0.12065 0.2794)
			(end -0.12065 0.3048)
			(stroke
				(width 0.1)
				(type default)
			)
			(layer "F.Fab")
		)
		(fp_line
			(start 0.120396 0.2794)
			(end -0.12065 0.2794)
			(stroke
				(width 0.1)
				(type default)
			)
			(layer "F.Fab")
		)
		(fp_line
			(start -0.12065 -0.2794)
			(end 0.12065 -0.2794)
			(stroke
				(width 0.1)
				(type default)
			)
			(layer "F.Fab")
		)
		(fp_line
			(start 0.12065 -0.2794)
			(end 0.12065 -0.3048)
			(stroke
				(width 0.1)
				(type default)
			)
			(layer "F.Fab")
		)
		(fp_line
			(start 0.12065 -0.3048)
			(end 0.67945 -0.3048)
			(stroke
				(width 0.1)
				(type default)
			)
			(layer "F.Fab")
		)
		(fp_line
			(start 0.67945 -0.3048)
			(end 0.67945 0.3048)
			(stroke
				(width 0.1)
				(type default)
			)
			(layer "F.Fab")
		)
		(fp_line
			(start -0.67945 -0.305054)
			(end -0.12065 -0.305054)
			(stroke
				(width 0.1)
				(type default)
			)
			(layer "F.Fab")
		)
		(fp_line
			(start -0.12065 -0.305054)
			(end -0.12065 -0.2794)
			(stroke
				(width 0.1)
				(type default)
			)
			(layer "F.Fab")
		)
		(pad "1" smd circle
			(at -0.40005 0 270)
			(size 0 0)
			(layers "F.Cu" "F.Mask" "F.Paste")
			(net "P3V3_NIC0")
		)
		(pad "2" smd circle
			(at 0.40005 0 270)
			(size 0 0)
			(layers "F.Cu" "F.Mask" "F.Paste")
			(net "GND")
		)
	)
	(footprint ""
		(layer "F.Cu")
		(at 235.619544 -148.736812 180)
		(property "Reference" "R1212"
			(at 0 0 180)
			(layer "F.SilkS")
			(hide yes)
			(effects
				(font
					(size 1.27 1.27)
				)
			)
		)
		(property "Value" ""
			(at 0 0 180)
			(layer "F.Fab")
			(effects
				(font
					(size 1.27 1.27)
				)
			)
		)
		(duplicate_pad_numbers_are_jumpers no)
		(fp_line
			(start -0.7874 -0.4064)
			(end 0.7874 -0.4064)
			(stroke
				(width 0.1524)
				(type default)
			)
			(layer "F.SilkS")
		)
		(fp_line
			(start 0.67945 0.3048)
			(end 0.120396 0.3048)
			(stroke
				(width 0.1)
				(type default)
			)
			(layer "F.Fab")
		)
		(fp_line
			(start 0.67945 -0.3048)
			(end 0.67945 0.3048)
			(stroke
				(width 0.1)
				(type default)
			)
			(layer "F.Fab")
		)
		(fp_line
			(start 0.12065 -0.2794)
			(end 0.12065 -0.3048)
			(stroke
				(width 0.1)
				(type default)
			)
			(layer "F.Fab")
		)
		(fp_line
			(start 0.12065 -0.3048)
			(end 0.67945 -0.3048)
			(stroke
				(width 0.1)
				(type default)
			)
			(layer "F.Fab")
		)
		(fp_line
			(start 0.120396 0.3048)
			(end 0.120396 0.2794)
			(stroke
				(width 0.1)
				(type default)
			)
			(layer "F.Fab")
		)
		(fp_line
			(start 0.120396 0.2794)
			(end -0.12065 0.2794)
			(stroke
				(width 0.1)
				(type default)
			)
			(layer "F.Fab")
		)
		(fp_line
			(start -0.12065 0.3048)
			(end -0.67945 0.3048)
			(stroke
				(width 0.1)
				(type default)
			)
			(layer "F.Fab")
		)
		(fp_line
			(start -0.12065 0.2794)
			(end -0.12065 0.3048)
			(stroke
				(width 0.1)
				(type default)
			)
			(layer "F.Fab")
		)
		(fp_line
			(start -0.12065 -0.2794)
			(end 0.12065 -0.2794)
			(stroke
				(width 0.1)
				(type default)
			)
			(layer "F.Fab")
		)
		(fp_line
			(start -0.12065 -0.305054)
			(end -0.12065 -0.2794)
			(stroke
				(width 0.1)
				(type default)
			)
			(layer "F.Fab")
		)
		(fp_line
			(start -0.67945 0.3048)
			(end -0.67945 -0.305054)
			(stroke
				(width 0.1)
				(type default)
			)
			(layer "F.Fab")
		)
		(fp_line
			(start -0.67945 -0.305054)
			(end -0.12065 -0.305054)
			(stroke
				(width 0.1)
				(type default)
			)
			(layer "F.Fab")
		)
		(pad "1" smd circle
			(at -0.40005 0 180)
			(size 0 0)
			(layers "F.Cu" "F.Mask" "F.Paste")
			(net "CLK_100M_PEX3_REF_R_DN")
		)
		(pad "2" smd circle
			(at 0.40005 0 180)
			(size 0 0)
			(layers "F.Cu" "F.Mask" "F.Paste")
			(net "CLK_100M_PEX3_REF_DN")
		)
	)
	(footprint ""
		(layer "F.Cu")
		(at 406.36444 -141.6558 180)
		(property "Reference" "R341"
			(at 0 0 180)
			(layer "F.SilkS")
			(hide yes)
			(effects
				(font
					(size 1.27 1.27)
				)
			)
		)
		(property "Value" ""
			(at 0 0 180)
			(layer "F.Fab")
			(effects
				(font
					(size 1.27 1.27)
				)
			)
		)
		(duplicate_pad_numbers_are_jumpers no)
		(fp_line
			(start 0.7874 0.4064)
			(end -0.7874 0.4064)
			(stroke
				(width 0.1524)
				(type default)
			)
			(layer "F.SilkS")
		)
		(fp_line
			(start 0.7874 -0.4064)
			(end 0.7874 0.4064)
			(stroke
				(width 0.1524)
				(type default)
			)
			(layer "F.SilkS")
		)
		(fp_line
			(start -0.7874 0.4064)
			(end -0.7874 -0.4064)
			(stroke
				(width 0.1524)
				(type default)
			)
			(layer "F.SilkS")
		)
		(fp_line
			(start -0.7874 -0.4064)
			(end 0.7874 -0.4064)
			(stroke
				(width 0.1524)
				(type default)
			)
			(layer "F.SilkS")
		)
		(fp_line
			(start 0.67945 0.3048)
			(end 0.120396 0.3048)
			(stroke
				(width 0.1)
				(type default)
			)
			(layer "F.Fab")
		)
		(fp_line
			(start 0.67945 -0.3048)
			(end 0.67945 0.3048)
			(stroke
				(width 0.1)
				(type default)
			)
			(layer "F.Fab")
		)
		(fp_line
			(start 0.12065 -0.2794)
			(end 0.12065 -0.3048)
			(stroke
				(width 0.1)
				(type default)
			)
			(layer "F.Fab")
		)
		(fp_line
			(start 0.12065 -0.3048)
			(end 0.67945 -0.3048)
			(stroke
				(width 0.1)
				(type default)
			)
			(layer "F.Fab")
		)
		(fp_line
			(start 0.120396 0.3048)
			(end 0.120396 0.2794)
			(stroke
				(width 0.1)
				(type default)
			)
			(layer "F.Fab")
		)
		(fp_line
			(start 0.120396 0.2794)
			(end -0.12065 0.2794)
			(stroke
				(width 0.1)
				(type default)
			)
			(layer "F.Fab")
		)
		(fp_line
			(start -0.12065 0.3048)
			(end -0.67945 0.3048)
			(stroke
				(width 0.1)
				(type default)
			)
			(layer "F.Fab")
		)
		(fp_line
			(start -0.12065 0.2794)
			(end -0.12065 0.3048)
			(stroke
				(width 0.1)
				(type default)
			)
			(layer "F.Fab")
		)
		(fp_line
			(start -0.12065 -0.2794)
			(end 0.12065 -0.2794)
			(stroke
				(width 0.1)
				(type default)
			)
			(layer "F.Fab")
		)
		(fp_line
			(start -0.12065 -0.305054)
			(end -0.12065 -0.2794)
			(stroke
				(width 0.1)
				(type default)
			)
			(layer "F.Fab")
		)
		(fp_line
			(start -0.67945 0.3048)
			(end -0.67945 -0.305054)
			(stroke
				(width 0.1)
				(type default)
			)
			(layer "F.Fab")
		)
		(fp_line
			(start -0.67945 -0.305054)
			(end -0.12065 -0.305054)
			(stroke
				(width 0.1)
				(type default)
			)
			(layer "F.Fab")
		)
		(pad "1" smd circle
			(at -0.40005 0 180)
			(size 0 0)
			(layers "F.Cu" "F.Mask" "F.Paste")
			(net "RST_SMB_NIC6_MUX_ISO_N")
		)
		(pad "2" smd circle
			(at 0.40005 0 180)
			(size 0 0)
			(layers "F.Cu" "F.Mask" "F.Paste")
			(net "P3V3_NIC6")
		)
	)
	(footprint ""
		(layer "F.Cu")
		(at 4.541266 -372.011448)
		(property "Reference" "R6759"
			(at 0 0 0)
			(layer "F.SilkS")
			(hide yes)
			(effects
				(font
					(size 1.27 1.27)
				)
			)
		)
		(property "Value" ""
			(at 0 0 0)
			(layer "F.Fab")
			(effects
				(font
					(size 1.27 1.27)
				)
			)
		)
		(duplicate_pad_numbers_are_jumpers no)
		(fp_line
			(start -0.7874 -0.4064)
			(end 0.7874 -0.4064)
			(stroke
				(width 0.1524)
				(type default)
			)
			(layer "F.SilkS")
		)
		(fp_line
			(start -0.7874 0.4064)
			(end -0.7874 -0.4064)
			(stroke
				(width 0.1524)
				(type default)
			)
			(layer "F.SilkS")
		)
		(fp_line
			(start 0.7874 -0.4064)
			(end 0.7874 0.4064)
			(stroke
				(width 0.1524)
				(type default)
			)
			(layer "F.SilkS")
		)
		(fp_line
			(start 0.7874 0.4064)
			(end -0.7874 0.4064)
			(stroke
				(width 0.1524)
				(type default)
			)
			(layer "F.SilkS")
		)
		(fp_line
			(start -0.67945 -0.305054)
			(end -0.12065 -0.305054)
			(stroke
				(width 0.1)
				(type default)
			)
			(layer "F.Fab")
		)
		(fp_line
			(start -0.67945 0.3048)
			(end -0.67945 -0.305054)
			(stroke
				(width 0.1)
				(type default)
			)
			(layer "F.Fab")
		)
		(fp_line
			(start -0.12065 -0.305054)
			(end -0.12065 -0.2794)
			(stroke
				(width 0.1)
				(type default)
			)
			(layer "F.Fab")
		)
		(fp_line
			(start -0.12065 -0.2794)
			(end 0.12065 -0.2794)
			(stroke
				(width 0.1)
				(type default)
			)
			(layer "F.Fab")
		)
		(fp_line
			(start -0.12065 0.2794)
			(end -0.12065 0.3048)
			(stroke
				(width 0.1)
				(type default)
			)
			(layer "F.Fab")
		)
		(fp_line
			(start -0.12065 0.3048)
			(end -0.67945 0.3048)
			(stroke
				(width 0.1)
				(type default)
			)
			(layer "F.Fab")
		)
		(fp_line
			(start 0.120396 0.2794)
			(end -0.12065 0.2794)
			(stroke
				(width 0.1)
				(type default)
			)
			(layer "F.Fab")
		)
		(fp_line
			(start 0.120396 0.3048)
			(end 0.120396 0.2794)
			(stroke
				(width 0.1)
				(type default)
			)
			(layer "F.Fab")
		)
		(fp_line
			(start 0.12065 -0.3048)
			(end 0.67945 -0.3048)
			(stroke
				(width 0.1)
				(type default)
			)
			(layer "F.Fab")
		)
		(fp_line
			(start 0.12065 -0.2794)
			(end 0.12065 -0.3048)
			(stroke
				(width 0.1)
				(type default)
			)
			(layer "F.Fab")
		)
		(fp_line
			(start 0.67945 -0.3048)
			(end 0.67945 0.3048)
			(stroke
				(width 0.1)
				(type default)
			)
			(layer "F.Fab")
		)
		(fp_line
			(start 0.67945 0.3048)
			(end 0.120396 0.3048)
			(stroke
				(width 0.1)
				(type default)
			)
			(layer "F.Fab")
		)
		(pad "1" smd circle
			(at -0.40005 0)
			(size 0 0)
			(layers "F.Cu" "F.Mask" "F.Paste")
			(net "P3V3_USB_HUB")
		)
		(pad "2" smd circle
			(at 0.40005 0)
			(size 0 0)
			(layers "F.Cu" "F.Mask" "F.Paste")
			(net "GND")
		)
	)
	(footprint ""
		(layer "F.Cu")
		(at 147.756372 -61.487812 180)
		(property "Reference" "R5973"
			(at 0 0 180)
			(layer "F.SilkS")
			(hide yes)
			(effects
				(font
					(size 1.27 1.27)
				)
			)
		)
		(property "Value" ""
			(at 0 0 180)
			(layer "F.Fab")
			(effects
				(font
					(size 1.27 1.27)
				)
			)
		)
		(duplicate_pad_numbers_are_jumpers no)
		(fp_line
			(start 0.7874 0.4064)
			(end -0.7874 0.4064)
			(stroke
				(width 0.1524)
				(type default)
			)
			(layer "F.SilkS")
		)
		(fp_line
			(start 0.7874 -0.4064)
			(end 0.7874 0.4064)
			(stroke
				(width 0.1524)
				(type default)
			)
			(layer "F.SilkS")
		)
		(fp_line
			(start -0.7874 0.4064)
			(end -0.7874 -0.4064)
			(stroke
				(width 0.1524)
				(type default)
			)
			(layer "F.SilkS")
		)
		(fp_line
			(start -0.7874 -0.4064)
			(end 0.7874 -0.4064)
			(stroke
				(width 0.1524)
				(type default)
			)
			(layer "F.SilkS")
		)
		(fp_line
			(start 0.67945 0.3048)
			(end 0.120396 0.3048)
			(stroke
				(width 0.1)
				(type default)
			)
			(layer "F.Fab")
		)
		(fp_line
			(start 0.67945 -0.3048)
			(end 0.67945 0.3048)
			(stroke
				(width 0.1)
				(type default)
			)
			(layer "F.Fab")
		)
		(fp_line
			(start 0.12065 -0.2794)
			(end 0.12065 -0.3048)
			(stroke
				(width 0.1)
				(type default)
			)
			(layer "F.Fab")
		)
		(fp_line
			(start 0.12065 -0.3048)
			(end 0.67945 -0.3048)
			(stroke
				(width 0.1)
				(type default)
			)
			(layer "F.Fab")
		)
		(fp_line
			(start 0.120396 0.3048)
			(end 0.120396 0.2794)
			(stroke
				(width 0.1)
				(type default)
			)
			(layer "F.Fab")
		)
		(fp_line
			(start 0.120396 0.2794)
			(end -0.12065 0.2794)
			(stroke
				(width 0.1)
				(type default)
			)
			(layer "F.Fab")
		)
		(fp_line
			(start -0.12065 0.3048)
			(end -0.67945 0.3048)
			(stroke
				(width 0.1)
				(type default)
			)
			(layer "F.Fab")
		)
		(fp_line
			(start -0.12065 0.2794)
			(end -0.12065 0.3048)
			(stroke
				(width 0.1)
				(type default)
			)
			(layer "F.Fab")
		)
		(fp_line
			(start -0.12065 -0.2794)
			(end 0.12065 -0.2794)
			(stroke
				(width 0.1)
				(type default)
			)
			(layer "F.Fab")
		)
		(fp_line
			(start -0.12065 -0.305054)
			(end -0.12065 -0.2794)
			(stroke
				(width 0.1)
				(type default)
			)
			(layer "F.Fab")
		)
		(fp_line
			(start -0.67945 0.3048)
			(end -0.67945 -0.305054)
			(stroke
				(width 0.1)
				(type default)
			)
			(layer "F.Fab")
		)
		(fp_line
			(start -0.67945 -0.305054)
			(end -0.12065 -0.305054)
			(stroke
				(width 0.1)
				(type default)
			)
			(layer "F.Fab")
		)
		(pad "1" smd circle
			(at -0.40005 0 180)
			(size 0 0)
			(layers "F.Cu" "F.Mask" "F.Paste")
			(net "P3V3_AUX")
		)
		(pad "2" smd circle
			(at 0.40005 0 180)
			(size 0 0)
			(layers "F.Cu" "F.Mask" "F.Paste")
			(net "PWRGD_P12V_SSD5_D")
		)
	)
	(footprint ""
		(layer "F.Cu")
		(at 80.019398 -123.184666 180)
		(property "Reference" "C27"
			(at 0 0 180)
			(layer "F.SilkS")
			(hide yes)
			(effects
				(font
					(size 1.27 1.27)
				)
			)
		)
		(property "Value" ""
			(at 0 0 180)
			(layer "F.Fab")
			(effects
				(font
					(size 1.27 1.27)
				)
			)
		)
		(duplicate_pad_numbers_are_jumpers no)
		(fp_line
			(start 0.299974 0.150114)
			(end -0.299974 0.150114)
			(stroke
				(width 0.1)
				(type default)
			)
			(layer "F.Fab")
		)
		(fp_line
			(start 0.299974 -0.150114)
			(end 0.299974 0.150114)
			(stroke
				(width 0.1)
				(type default)
			)
			(layer "F.Fab")
		)
		(fp_line
			(start -0.299974 0.150114)
			(end -0.299974 -0.150114)
			(stroke
				(width 0.1)
				(type default)
			)
			(layer "F.Fab")
		)
		(fp_line
			(start -0.299974 -0.150114)
			(end 0.299974 -0.150114)
			(stroke
				(width 0.1)
				(type default)
			)
			(layer "F.Fab")
		)
		(pad "1" smd rect
			(at -0.2667 0 180)
			(size 0.3048 0.381)
			(layers "F.Cu" "F.Mask" "F.Paste")
			(net "P5E_PEX0_STN0_TX_DP<2>")
		)
		(pad "2" smd rect
			(at 0.2667 0 180)
			(size 0.3048 0.381)
			(layers "F.Cu" "F.Mask" "F.Paste")
			(net "P5E_PEX0_STN0_TX_C_DP<2>")
		)
	)
)
